(kicad_pcb
	(version 20260206)
	(generator "pcbnew")
	(generator_version "10.0")
	(general
		(thickness 1.6)
		(legacy_teardrops no)
	)
	(paper "A4")
	(title_block
		(title "04192023_DAF0TMB3IC0_F0TG_MB_C_brd_V02_OCP.brd")
		(comment 1 "Grand Teton / footprints 4130-4136 of 8354")
	)
	(layers
		(0 "F.Cu" signal "TOP")
		(4 "In1.Cu" signal "GND")
		(6 "In2.Cu" signal "IN1")
		(8 "In3.Cu" signal "GND1")
		(10 "In4.Cu" signal "IN2")
		(12 "In5.Cu" signal "GND2")
		(14 "In6.Cu" signal "IN3")
		(16 "In7.Cu" signal "GND3")
		(18 "In8.Cu" signal "VCC")
		(20 "In9.Cu" signal "VCC1")
		(22 "In10.Cu" signal "GND4")
		(24 "In11.Cu" signal "IN4")
		(26 "In12.Cu" signal "GND5")
		(28 "In13.Cu" signal "IN5")
		(30 "In14.Cu" signal "GND6")
		(32 "In15.Cu" signal "IN6")
		(34 "In16.Cu" signal "GND7")
		(2 "B.Cu" signal "BOTTOM")
		(9 "F.Adhes" user "F.Adhesive")
		(11 "B.Adhes" user "B.Adhesive")
		(13 "F.Paste" user "Package Geometry/Pastemask Top")
		(15 "B.Paste" user "Package Geometry/Pastemask Bottom")
		(5 "F.SilkS" user "Ref Des/Silkscreen Top")
		(7 "B.SilkS" user "Ref Des/Silkscreen Bottom")
		(1 "F.Mask" user "Board Geometry/Soldermask Top")
		(3 "B.Mask" user "Board Geometry/Soldermask Bottom")
		(17 "Dwgs.User" user "User.Drawings")
		(19 "Cmts.User" user "User.Comments")
		(21 "Eco1.User" user "User.Eco1")
		(23 "Eco2.User" user "User.Eco2")
		(25 "Edge.Cuts" user "Board Geometry/Outline")
		(27 "Margin" user)
		(31 "F.CrtYd" user "Package Geometry/Place Bound Top")
		(29 "B.CrtYd" user "Package Geometry/Place Bound Bottom")
		(35 "F.Fab" user "Ref Des/Assembly Top")
		(33 "B.Fab" user "Ref Des/Assembly Bottom")
	)
	(footprint ""
		(layer "F.Cu")
		(at 125.992636 -60.482226)
		(property "Reference" "R1727"
			(at 0 0 0)
			(layer "F.SilkS")
			(hide yes)
			(effects
				(font
					(size 1.27 1.27)
				)
			)
		)
		(property "Value" ""
			(at 0 0 0)
			(layer "F.Fab")
			(effects
				(font
					(size 1.27 1.27)
				)
			)
		)
		(duplicate_pad_numbers_are_jumpers no)
		(fp_line
			(start -0.7874 -0.4064)
			(end 0.7874 -0.4064)
			(stroke
				(width 0.1524)
				(type default)
			)
			(layer "F.SilkS")
		)
		(fp_line
			(start -0.7874 0.4064)
			(end -0.7874 -0.4064)
			(stroke
				(width 0.1524)
				(type default)
			)
			(layer "F.SilkS")
		)
		(fp_line
			(start 0.7874 -0.4064)
			(end 0.7874 0.4064)
			(stroke
				(width 0.1524)
				(type default)
			)
			(layer "F.SilkS")
		)
		(fp_line
			(start 0.7874 0.4064)
			(end -0.7874 0.4064)
			(stroke
				(width 0.1524)
				(type default)
			)
			(layer "F.SilkS")
		)
		(fp_line
			(start -0.67945 -0.305054)
			(end -0.12065 -0.305054)
			(stroke
				(width 0.1)
				(type default)
			)
			(layer "F.Fab")
		)
		(fp_line
			(start -0.67945 0.3048)
			(end -0.67945 -0.305054)
			(stroke
				(width 0.1)
				(type default)
			)
			(layer "F.Fab")
		)
		(fp_line
			(start -0.12065 -0.305054)
			(end -0.12065 -0.2794)
			(stroke
				(width 0.1)
				(type default)
			)
			(layer "F.Fab")
		)
		(fp_line
			(start -0.12065 -0.2794)
			(end 0.12065 -0.2794)
			(stroke
				(width 0.1)
				(type default)
			)
			(layer "F.Fab")
		)
		(fp_line
			(start -0.12065 0.2794)
			(end -0.12065 0.3048)
			(stroke
				(width 0.1)
				(type default)
			)
			(layer "F.Fab")
		)
		(fp_line
			(start -0.12065 0.3048)
			(end -0.67945 0.3048)
			(stroke
				(width 0.1)
				(type default)
			)
			(layer "F.Fab")
		)
		(fp_line
			(start 0.120396 0.2794)
			(end -0.12065 0.2794)
			(stroke
				(width 0.1)
				(type default)
			)
			(layer "F.Fab")
		)
		(fp_line
			(start 0.120396 0.3048)
			(end 0.120396 0.2794)
			(stroke
				(width 0.1)
				(type default)
			)
			(layer "F.Fab")
		)
		(fp_line
			(start 0.12065 -0.3048)
			(end 0.67945 -0.3048)
			(stroke
				(width 0.1)
				(type default)
			)
			(layer "F.Fab")
		)
		(fp_line
			(start 0.12065 -0.2794)
			(end 0.12065 -0.3048)
			(stroke
				(width 0.1)
				(type default)
			)
			(layer "F.Fab")
		)
		(fp_line
			(start 0.67945 -0.3048)
			(end 0.67945 0.3048)
			(stroke
				(width 0.1)
				(type default)
			)
			(layer "F.Fab")
		)
		(fp_line
			(start 0.67945 0.3048)
			(end 0.120396 0.3048)
			(stroke
				(width 0.1)
				(type default)
			)
			(layer "F.Fab")
		)
		(pad "1" smd circle
			(at -0.40005 0)
			(size 0 0)
			(layers "F.Cu" "F.Mask" "F.Paste")
			(net "P3V3_AUX")
		)
		(pad "2" smd circle
			(at 0.40005 0)
			(size 0 0)
			(layers "F.Cu" "F.Mask" "F.Paste")
			(net "JTAG_SCM_TDO")
		)
	)
	(footprint ""
		(layer "F.Cu")
		(at 86.868 -70.866 -90)
		(property "Reference" "R1171"
			(at 0 0 270)
			(layer "F.SilkS")
			(hide yes)
			(effects
				(font
					(size 1.27 1.27)
				)
			)
		)
		(property "Value" ""
			(at 0 0 270)
			(layer "F.Fab")
			(effects
				(font
					(size 1.27 1.27)
				)
			)
		)
		(duplicate_pad_numbers_are_jumpers no)
		(fp_line
			(start -0.7874 0.4064)
			(end -0.7874 -0.4064)
			(stroke
				(width 0.1524)
				(type default)
			)
			(layer "F.SilkS")
		)
		(fp_line
			(start 0.7874 0.4064)
			(end -0.7874 0.4064)
			(stroke
				(width 0.1524)
				(type default)
			)
			(layer "F.SilkS")
		)
		(fp_line
			(start -0.7874 -0.4064)
			(end 0.7874 -0.4064)
			(stroke
				(width 0.1524)
				(type default)
			)
			(layer "F.SilkS")
		)
		(fp_line
			(start 0.7874 -0.4064)
			(end 0.7874 0.4064)
			(stroke
				(width 0.1524)
				(type default)
			)
			(layer "F.SilkS")
		)
		(fp_line
			(start -0.67945 0.3048)
			(end -0.67945 -0.305054)
			(stroke
				(width 0.1)
				(type default)
			)
			(layer "F.Fab")
		)
		(fp_line
			(start -0.12065 0.3048)
			(end -0.67945 0.3048)
			(stroke
				(width 0.1)
				(type default)
			)
			(layer "F.Fab")
		)
		(fp_line
			(start 0.120396 0.3048)
			(end 0.120396 0.2794)
			(stroke
				(width 0.1)
				(type default)
			)
			(layer "F.Fab")
		)
		(fp_line
			(start 0.67945 0.3048)
			(end 0.120396 0.3048)
			(stroke
				(width 0.1)
				(type default)
			)
			(layer "F.Fab")
		)
		(fp_line
			(start -0.12065 0.2794)
			(end -0.12065 0.3048)
			(stroke
				(width 0.1)
				(type default)
			)
			(layer "F.Fab")
		)
		(fp_line
			(start 0.120396 0.2794)
			(end -0.12065 0.2794)
			(stroke
				(width 0.1)
				(type default)
			)
			(layer "F.Fab")
		)
		(fp_line
			(start -0.12065 -0.2794)
			(end 0.12065 -0.2794)
			(stroke
				(width 0.1)
				(type default)
			)
			(layer "F.Fab")
		)
		(fp_line
			(start 0.12065 -0.2794)
			(end 0.12065 -0.3048)
			(stroke
				(width 0.1)
				(type default)
			)
			(layer "F.Fab")
		)
		(fp_line
			(start 0.12065 -0.3048)
			(end 0.67945 -0.3048)
			(stroke
				(width 0.1)
				(type default)
			)
			(layer "F.Fab")
		)
		(fp_line
			(start 0.67945 -0.3048)
			(end 0.67945 0.3048)
			(stroke
				(width 0.1)
				(type default)
			)
			(layer "F.Fab")
		)
		(fp_line
			(start -0.67945 -0.305054)
			(end -0.12065 -0.305054)
			(stroke
				(width 0.1)
				(type default)
			)
			(layer "F.Fab")
		)
		(fp_line
			(start -0.12065 -0.305054)
			(end -0.12065 -0.2794)
			(stroke
				(width 0.1)
				(type default)
			)
			(layer "F.Fab")
		)
		(pad "1" smd circle
			(at -0.40005 0 270)
			(size 0 0)
			(layers "F.Cu" "F.Mask" "F.Paste")
			(net "P3V3_AUX")
		)
		(pad "2" smd circle
			(at 0.40005 0 270)
			(size 0 0)
			(layers "F.Cu" "F.Mask" "F.Paste")
			(net "OCP_V3_2_P3V3_PLD_R_PWRGD")
		)
	)
	(footprint ""
		(layer "F.Cu")
		(at 419.167564 -16.100298 90)
		(property "Reference" "C1569"
			(at 0 0 90)
			(layer "F.SilkS")
			(hide yes)
			(effects
				(font
					(size 1.27 1.27)
				)
			)
		)
		(property "Value" ""
			(at 0 0 90)
			(layer "F.Fab")
			(effects
				(font
					(size 1.27 1.27)
				)
			)
		)
		(duplicate_pad_numbers_are_jumpers no)
		(fp_line
			(start 0.299974 -0.150114)
			(end 0.299974 0.150114)
			(stroke
				(width 0.1)
				(type default)
			)
			(layer "F.Fab")
		)
		(fp_line
			(start -0.299974 -0.150114)
			(end 0.299974 -0.150114)
			(stroke
				(width 0.1)
				(type default)
			)
			(layer "F.Fab")
		)
		(fp_line
			(start 0.299974 0.150114)
			(end -0.299974 0.150114)
			(stroke
				(width 0.1)
				(type default)
			)
			(layer "F.Fab")
		)
		(fp_line
			(start -0.299974 0.150114)
			(end -0.299974 -0.150114)
			(stroke
				(width 0.1)
				(type default)
			)
			(layer "F.Fab")
		)
		(pad "1" smd rect
			(at -0.2667 0 90)
			(size 0.3048 0.381)
			(layers "F.Cu" "F.Mask" "F.Paste")
			(net "P5E_CPU0_G3_TX_C_DP<5>")
		)
		(pad "2" smd rect
			(at 0.2667 0 90)
			(size 0.3048 0.381)
			(layers "F.Cu" "F.Mask" "F.Paste")
			(net "P5E_CPU0_G3_TX_DP<5>")
		)
	)
	(footprint ""
		(layer "F.Cu")
		(at 398.155668 -395.333474)
		(property "Reference" "R614"
			(at 0 0 0)
			(layer "F.SilkS")
			(hide yes)
			(effects
				(font
					(size 1.27 1.27)
				)
			)
		)
		(property "Value" ""
			(at 0 0 0)
			(layer "F.Fab")
			(effects
				(font
					(size 1.27 1.27)
				)
			)
		)
		(duplicate_pad_numbers_are_jumpers no)
		(fp_line
			(start -0.32512 -0.175006)
			(end 0.32512 -0.175006)
			(stroke
				(width 0.1)
				(type default)
			)
			(layer "F.Fab")
		)
		(fp_line
			(start -0.32512 0.175006)
			(end -0.32512 -0.175006)
			(stroke
				(width 0.1)
				(type default)
			)
			(layer "F.Fab")
		)
		(fp_line
			(start 0.32512 -0.175006)
			(end 0.32512 0.175006)
			(stroke
				(width 0.1)
				(type default)
			)
			(layer "F.Fab")
		)
		(fp_line
			(start 0.32512 0.175006)
			(end -0.32512 0.175006)
			(stroke
				(width 0.1)
				(type default)
			)
			(layer "F.Fab")
		)
		(pad "1" smd rect
			(at -0.2667 0)
			(size 0.3048 0.381)
			(layers "F.Cu" "F.Mask" "F.Paste")
			(net "CLK_100M_RETIMER_CPU0_P2_R_DN")
		)
		(pad "2" smd rect
			(at 0.2667 0 180)
			(size 0.3048 0.381)
			(layers "F.Cu" "F.Mask" "F.Paste")
			(net "CLK_100M_RETIMER_CPU0_P2_DN")
		)
	)
	(footprint ""
		(layer "F.Cu")
		(at 164.544756 -43.193462)
		(property "Reference" "R153"
			(at 0 0 0)
			(layer "F.SilkS")
			(hide yes)
			(effects
				(font
					(size 1.27 1.27)
				)
			)
		)
		(property "Value" ""
			(at 0 0 0)
			(layer "F.Fab")
			(effects
				(font
					(size 1.27 1.27)
				)
			)
		)
		(duplicate_pad_numbers_are_jumpers no)
		(fp_line
			(start -0.7874 -0.4064)
			(end 0.7874 -0.4064)
			(stroke
				(width 0.1524)
				(type default)
			)
			(layer "F.SilkS")
		)
		(fp_line
			(start -0.7874 0.4064)
			(end -0.7874 -0.4064)
			(stroke
				(width 0.1524)
				(type default)
			)
			(layer "F.SilkS")
		)
		(fp_line
			(start 0.7874 -0.4064)
			(end 0.7874 0.4064)
			(stroke
				(width 0.1524)
				(type default)
			)
			(layer "F.SilkS")
		)
		(fp_line
			(start 0.7874 0.4064)
			(end -0.7874 0.4064)
			(stroke
				(width 0.1524)
				(type default)
			)
			(layer "F.SilkS")
		)
		(fp_line
			(start -0.67945 -0.305054)
			(end -0.12065 -0.305054)
			(stroke
				(width 0.1)
				(type default)
			)
			(layer "F.Fab")
		)
		(fp_line
			(start -0.67945 0.3048)
			(end -0.67945 -0.305054)
			(stroke
				(width 0.1)
				(type default)
			)
			(layer "F.Fab")
		)
		(fp_line
			(start -0.12065 -0.305054)
			(end -0.12065 -0.2794)
			(stroke
				(width 0.1)
				(type default)
			)
			(layer "F.Fab")
		)
		(fp_line
			(start -0.12065 -0.2794)
			(end 0.12065 -0.2794)
			(stroke
				(width 0.1)
				(type default)
			)
			(layer "F.Fab")
		)
		(fp_line
			(start -0.12065 0.2794)
			(end -0.12065 0.3048)
			(stroke
				(width 0.1)
				(type default)
			)
			(layer "F.Fab")
		)
		(fp_line
			(start -0.12065 0.3048)
			(end -0.67945 0.3048)
			(stroke
				(width 0.1)
				(type default)
			)
			(layer "F.Fab")
		)
		(fp_line
			(start 0.120396 0.2794)
			(end -0.12065 0.2794)
			(stroke
				(width 0.1)
				(type default)
			)
			(layer "F.Fab")
		)
		(fp_line
			(start 0.120396 0.3048)
			(end 0.120396 0.2794)
			(stroke
				(width 0.1)
				(type default)
			)
			(layer "F.Fab")
		)
		(fp_line
			(start 0.12065 -0.3048)
			(end 0.67945 -0.3048)
			(stroke
				(width 0.1)
				(type default)
			)
			(layer "F.Fab")
		)
		(fp_line
			(start 0.12065 -0.2794)
			(end 0.12065 -0.3048)
			(stroke
				(width 0.1)
				(type default)
			)
			(layer "F.Fab")
		)
		(fp_line
			(start 0.67945 -0.3048)
			(end 0.67945 0.3048)
			(stroke
				(width 0.1)
				(type default)
			)
			(layer "F.Fab")
		)
		(fp_line
			(start 0.67945 0.3048)
			(end 0.120396 0.3048)
			(stroke
				(width 0.1)
				(type default)
			)
			(layer "F.Fab")
		)
		(pad "1" smd circle
			(at -0.40005 0)
			(size 0 0)
			(layers "F.Cu" "F.Mask" "F.Paste")
			(net "M2_SSD0_CLKREQ_EN_N")
		)
		(pad "2" smd circle
			(at 0.40005 0)
			(size 0 0)
			(layers "F.Cu" "F.Mask" "F.Paste")
			(net "M2_SSD0_CLKREQ_EN_N_BUF")
		)
	)
	(footprint ""
		(layer "F.Cu")
		(at 193.167 -28.194 -90)
		(property "Reference" "R8030"
			(at 0 0 270)
			(layer "F.SilkS")
			(hide yes)
			(effects
				(font
					(size 1.27 1.27)
				)
			)
		)
		(property "Value" ""
			(at 0 0 270)
			(layer "F.Fab")
			(effects
				(font
					(size 1.27 1.27)
				)
			)
		)
		(duplicate_pad_numbers_are_jumpers no)
		(fp_line
			(start -0.7874 0.4064)
			(end -0.7874 -0.4064)
			(stroke
				(width 0.1524)
				(type default)
			)
			(layer "F.SilkS")
		)
		(fp_line
			(start 0.7874 0.4064)
			(end -0.7874 0.4064)
			(stroke
				(width 0.1524)
				(type default)
			)
			(layer "F.SilkS")
		)
		(fp_line
			(start -0.7874 -0.4064)
			(end 0.7874 -0.4064)
			(stroke
				(width 0.1524)
				(type default)
			)
			(layer "F.SilkS")
		)
		(fp_line
			(start 0.7874 -0.4064)
			(end 0.7874 0.4064)
			(stroke
				(width 0.1524)
				(type default)
			)
			(layer "F.SilkS")
		)
		(fp_line
			(start -0.67945 0.3048)
			(end -0.67945 -0.305054)
			(stroke
				(width 0.1)
				(type default)
			)
			(layer "F.Fab")
		)
		(fp_line
			(start -0.12065 0.3048)
			(end -0.67945 0.3048)
			(stroke
				(width 0.1)
				(type default)
			)
			(layer "F.Fab")
		)
		(fp_line
			(start 0.120396 0.3048)
			(end 0.120396 0.2794)
			(stroke
				(width 0.1)
				(type default)
			)
			(layer "F.Fab")
		)
		(fp_line
			(start 0.67945 0.3048)
			(end 0.120396 0.3048)
			(stroke
				(width 0.1)
				(type default)
			)
			(layer "F.Fab")
		)
		(fp_line
			(start -0.12065 0.2794)
			(end -0.12065 0.3048)
			(stroke
				(width 0.1)
				(type default)
			)
			(layer "F.Fab")
		)
		(fp_line
			(start 0.120396 0.2794)
			(end -0.12065 0.2794)
			(stroke
				(width 0.1)
				(type default)
			)
			(layer "F.Fab")
		)
		(fp_line
			(start -0.12065 -0.2794)
			(end 0.12065 -0.2794)
			(stroke
				(width 0.1)
				(type default)
			)
			(layer "F.Fab")
		)
		(fp_line
			(start 0.12065 -0.2794)
			(end 0.12065 -0.3048)
			(stroke
				(width 0.1)
				(type default)
			)
			(layer "F.Fab")
		)
		(fp_line
			(start 0.12065 -0.3048)
			(end 0.67945 -0.3048)
			(stroke
				(width 0.1)
				(type default)
			)
			(layer "F.Fab")
		)
		(fp_line
			(start 0.67945 -0.3048)
			(end 0.67945 0.3048)
			(stroke
				(width 0.1)
				(type default)
			)
			(layer "F.Fab")
		)
		(fp_line
			(start -0.67945 -0.305054)
			(end -0.12065 -0.305054)
			(stroke
				(width 0.1)
				(type default)
			)
			(layer "F.Fab")
		)
		(fp_line
			(start -0.12065 -0.305054)
			(end -0.12065 -0.2794)
			(stroke
				(width 0.1)
				(type default)
			)
			(layer "F.Fab")
		)
		(pad "1" smd circle
			(at -0.40005 0 270)
			(size 0 0)
			(layers "F.Cu" "F.Mask" "F.Paste")
			(net "P12V_SCM_FAULT_N")
		)
		(pad "2" smd circle
			(at 0.40005 0 270)
			(size 0 0)
			(layers "F.Cu" "F.Mask" "F.Paste")
			(net "P12V_SCM_FAULT_R_N")
		)
	)
	(footprint ""
		(layer "F.Cu")
		(at 291.706046 -368.230658)
		(property "Reference" "PQ14"
			(at 0.935482 -4.364482 0)
			(unlocked yes)
			(layer "F.SilkS")
			(effects
				(font
					(size 0.7874 0.5842)
					(thickness 0.1524)
				)
			)
		)
		(property "Value" ""
			(at 0 0 0)
			(layer "F.Fab")
			(effects
				(font
					(size 1.27 1.27)
				)
			)
		)
		(duplicate_pad_numbers_are_jumpers no)
		(fp_line
			(start -1.949958 -1.610106)
			(end 1.949958 -1.610106)
			(stroke
				(width 0.1524)
				(type default)
			)
			(layer "F.SilkS")
		)
		(fp_line
			(start -1.949958 1.610106)
			(end -1.949958 -1.610106)
			(stroke
				(width 0.1524)
				(type default)
			)
			(layer "F.SilkS")
		)
		(fp_line
			(start 1.949958 -1.560068)
			(end 1.949958 1.610106)
			(stroke
				(width 0.1524)
				(type default)
			)
			(layer "F.SilkS")
		)
		(fp_line
			(start 1.949958 1.610106)
			(end -1.949958 1.610106)
			(stroke
				(width 0.1524)
				(type default)
			)
			(layer "F.SilkS")
		)
		(fp_line
			(start -0.750062 -1.560068)
			(end 0.750062 -1.560068)
			(stroke
				(width 0.1)
				(type default)
			)
			(layer "F.Fab")
		)
		(fp_line
			(start -0.750062 1.560068)
			(end -0.750062 -1.560068)
			(stroke
				(width 0.1)
				(type default)
			)
			(layer "F.Fab")
		)
		(fp_line
			(start 0.750062 -1.560068)
			(end 0.750062 1.560068)
			(stroke
				(width 0.1)
				(type default)
			)
			(layer "F.Fab")
		)
		(fp_line
			(start 0.750062 1.560068)
			(end -0.750062 1.560068)
			(stroke
				(width 0.1)
				(type default)
			)
			(layer "F.Fab")
		)
		(pad "D" smd rect
			(at 1.100074 0 270)
			(size 1.016 1.4224)
			(layers "F.Cu" "F.Mask" "F.Paste")
			(net "PVDDIO_P0_EN_G")
		)
		(pad "G" smd rect
			(at -1.100074 -0.94996 270)
			(size 1.016 1.4224)
			(layers "F.Cu" "F.Mask" "F.Paste")
			(net "PVDDIO_P0_EN_R")
		)
		(pad "S" smd rect
			(at -1.100074 0.94996 270)
			(size 1.016 1.4224)
			(layers "F.Cu" "F.Mask" "F.Paste")
			(net "GND")
		)
	)
)
